# TIMECARD (Time Appliance Project (Time Card)) — schematic netlist excerpt (pin names and nets, part order shuffled) for the footprints in the layout excerpt that follows; sources: Cadence DE-HDL packaged netlist, KiCad conversion of R4006-B0001-02_R01.brd

R32  RESISTOR  3.24KOHM 1%  pkg SMC_0402R_H014  page 32 : \1\ = XP5R0V_FB_R_TO_AGND ; \2\ = XP5R0V_AGND
C109  CAPACITOR  0.1UF 10V 10%  pkg SMC_0402R_H022  page 14 : \1\ = XP1R0V_FPGA_VCCINT ; \2\ = SG

(kicad_pcb
	(version 20260206)
	(generator "pcbnew")
	(generator_version "10.0")
	(general
		(thickness 1.6)
		(legacy_teardrops no)
	)
	(paper "A4")
	(title_block
		(title "timecard-production-celestica-r4006 — R4006-B0001-02_R01.brd")
		(comment 1 "Time Appliance Project (Time Card) / footprints 849-850 of 1113")
	)
	(layers
		(0 "F.Cu" signal "TOP")
		(4 "In1.Cu" signal "L02_GND1")
		(6 "In2.Cu" signal "L03_SIG1")
		(8 "In3.Cu" signal "L04_GND2")
		(10 "In4.Cu" signal "L05_VCC1")
		(12 "In5.Cu" signal "L06_VCC2")
		(14 "In6.Cu" signal "L07_GND3")
		(16 "In7.Cu" signal "L08_SIG2")
		(18 "In8.Cu" signal "L09_GND4")
		(2 "B.Cu" signal "BOTTOM")
		(9 "F.Adhes" user "F.Adhesive")
		(11 "B.Adhes" user "B.Adhesive")
		(13 "F.Paste" user "Package Geometry/Pastemask Top")
		(15 "B.Paste" user "Package Geometry/Pastemask Bottom")
		(5 "F.SilkS" user "Ref Des/Silkscreen Top")
		(7 "B.SilkS" user "Ref Des/Silkscreen Bottom")
		(1 "F.Mask" user "Board Geometry/Soldermask Top")
		(3 "B.Mask" user "Board Geometry/Soldermask Bottom")
		(17 "Dwgs.User" user "User.Drawings")
		(19 "Cmts.User" user "User.Comments")
		(21 "Eco1.User" user "User.Eco1")
		(23 "Eco2.User" user "User.Eco2")
		(25 "Edge.Cuts" user "Board Geometry/Outline")
		(27 "Margin" user)
		(31 "F.CrtYd" user "Package Geometry/Place Bound Top")
		(29 "B.CrtYd" user "Package Geometry/Place Bound Bottom")
		(35 "F.Fab" user "Ref Des/Assembly Top")
		(33 "B.Fab" user "Ref Des/Assembly Bottom")
	)
	(footprint ""
		(layer "B.Cu")
		(at 36.9824 -105.2068)
		(property "Reference" "R32"
			(at -2.8194 -0.68453 0)
			(unlocked yes)
			(layer "B.SilkS")
			(effects
				(font
					(size 0.7874 0.5842)
					(thickness 0.1524)
				)
				(justify mirror)
			)
		)
		(property "Value" "VAL*"
			(at -0.02032 2.13233 0)
			(unlocked yes)
			(layer "B.Fab")
			(hide yes)
			(effects
				(font
					(size 0.7874 0.5842)
					(thickness 0.1524)
				)
				(justify mirror)
			)
		)
		(property "Tolerance" "TOL*"
			(at -0.044704 3.05435 0)
			(unlocked yes)
			(layer "Cmts.User")
			(hide yes)
			(effects
				(font
					(size 0.7874 0.5842)
					(thickness 0.1524)
				)
				(justify mirror)
			)
		)
		(property "User Part Number" "PARTNUM*"
			(at -0.02032 4.024884 0)
			(unlocked yes)
			(layer "Cmts.User")
			(hide yes)
			(effects
				(font
					(size 0.7874 0.5842)
					(thickness 0.1524)
				)
				(justify mirror)
			)
		)
		(property "Device Type" "RESISTOR-G155-03241-01,3.24KOHA"
			(at -0.008382 1.210564 0)
			(unlocked yes)
			(layer "B.Fab")
			(hide yes)
			(effects
				(font
					(size 0.7874 0.5842)
					(thickness 0.1524)
				)
				(justify mirror)
			)
		)
		(duplicate_pad_numbers_are_jumpers no)
		(fp_line
			(start -1.143 -0.5588)
			(end 1.143 -0.5588)
			(stroke
				(width 0.1)
				(type default)
			)
			(layer "B.SilkS")
		)
		(fp_line
			(start -1.143 0.5588)
			(end -1.143 -0.5588)
			(stroke
				(width 0.1)
				(type default)
			)
			(layer "B.SilkS")
		)
		(fp_line
			(start 1.143 -0.5588)
			(end 1.143 0.5588)
			(stroke
				(width 0.1)
				(type default)
			)
			(layer "B.SilkS")
		)
		(fp_line
			(start 1.143 0.5588)
			(end -1.143 0.5588)
			(stroke
				(width 0.1)
				(type default)
			)
			(layer "B.SilkS")
		)
		(fp_poly
			(pts
				(xy 1.143 0.5588) (xy -1.143 0.5588) (xy -1.143 -0.5588) (xy 1.143 -0.5588)
			)
			(stroke
				(width 0)
				(type default)
			)
			(fill no)
			(layer "B.CrtYd")
		)
		(fp_line
			(start -0.508 -0.3048)
			(end 0.508 -0.3048)
			(stroke
				(width 0.1)
				(type default)
			)
			(layer "B.Fab")
		)
		(fp_line
			(start -0.508 0.3048)
			(end -0.508 -0.3048)
			(stroke
				(width 0.1)
				(type default)
			)
			(layer "B.Fab")
		)
		(fp_line
			(start 0.508 -0.3048)
			(end 0.508 0.3048)
			(stroke
				(width 0.1)
				(type default)
			)
			(layer "B.Fab")
		)
		(fp_line
			(start 0.508 0.3048)
			(end -0.508 0.3048)
			(stroke
				(width 0.1)
				(type default)
			)
			(layer "B.Fab")
		)
		(pad "1" smd rect
			(at 0.5334 0 180)
			(size 0.7112 0.6096)
			(layers "B.Cu" "B.Mask" "B.Paste")
			(net "XP5R0V_FB_R_TO_AGND")
		)
		(pad "2" smd rect
			(at -0.5334 0 180)
			(size 0.7112 0.6096)
			(layers "B.Cu" "B.Mask" "B.Paste")
			(net "XP5R0V_AGND")
		)
		(zone
			(layer "B.Cu")
			(hatch none 0.5)
			(connect_pads
				(clearance 0)
			)
			(min_thickness 0.25)
			(keepout
				(tracks allowed)
				(vias not_allowed)
				(pads allowed)
				(copperpour not_allowed)
				(footprints allowed)
			)
			(placement
				(enabled no)
				(sheetname "")
			)
			(fill
				(thermal_gap 0.5)
				(thermal_bridge_width 0.5)
				(island_removal_mode 0)
			)
			(polygon
				(pts
					(xy 37.0586 -104.902) (xy 37.0586 -105.5116) (xy 36.9062 -105.5116) (xy 36.9062 -104.902)
				)
			)
		)
		(zone
			(layer "B.Cu")
			(hatch none 0.5)
			(connect_pads
				(clearance 0)
			)
			(min_thickness 0.25)
			(keepout
				(tracks not_allowed)
				(vias allowed)
				(pads allowed)
				(copperpour not_allowed)
				(footprints allowed)
			)
			(placement
				(enabled no)
				(sheetname "")
			)
			(fill
				(thermal_gap 0.5)
				(thermal_bridge_width 0.5)
				(island_removal_mode 0)
			)
			(polygon
				(pts
					(xy 37.0586 -104.902) (xy 37.0586 -105.5116) (xy 36.9062 -105.5116) (xy 36.9062 -104.902)
				)
			)
		)
	)
	(footprint ""
		(layer "B.Cu")
		(at 107.347004 -42.82313)
		(property "Reference" "C109"
			(at -41.180004 0.94488 0)
			(unlocked yes)
			(layer "B.SilkS")
			(effects
				(font
					(size 0.635 0.4064)
					(thickness 0.1524)
				)
				(justify mirror)
			)
		)
		(property "Value" "VAL*"
			(at 0 3.718306 0)
			(unlocked yes)
			(layer "B.Fab")
			(hide yes)
			(effects
				(font
					(size 0.7874 0.5842)
					(thickness 0.127)
				)
				(justify mirror)
			)
		)
		(property "Device Type" "CAPACITOR-G105-0B104-CK,0.1UF,A"
			(at 0 1.432306 0)
			(unlocked yes)
			(layer "B.Fab")
			(hide yes)
			(effects
				(font
					(size 0.7874 0.5842)
					(thickness 0.127)
				)
				(justify mirror)
			)
		)
		(property "User Part Number" "PARTNUM*"
			(at 0 2.575306 0)
			(unlocked yes)
			(layer "Cmts.User")
			(hide yes)
			(effects
				(font
					(size 0.7874 0.5842)
					(thickness 0.127)
				)
				(justify mirror)
			)
		)
		(property "Tolerance" "TOL*"
			(at 0 4.861306 0)
			(unlocked yes)
			(layer "Cmts.User")
			(hide yes)
			(effects
				(font
					(size 0.7874 0.5842)
					(thickness 0.127)
				)
				(justify mirror)
			)
		)
		(duplicate_pad_numbers_are_jumpers no)
		(fp_line
			(start -0.970026 -0.4699)
			(end -0.970026 0.4699)
			(stroke
				(width 0.1)
				(type default)
			)
			(layer "B.SilkS")
		)
		(fp_line
			(start -0.970026 0.4699)
			(end 0.970026 0.4699)
			(stroke
				(width 0.1)
				(type default)
			)
			(layer "B.SilkS")
		)
		(fp_line
			(start 0.970026 -0.4699)
			(end -0.970026 -0.4699)
			(stroke
				(width 0.1)
				(type default)
			)
			(layer "B.SilkS")
		)
		(fp_line
			(start 0.970026 0.4699)
			(end 0.970026 -0.4699)
			(stroke
				(width 0.1)
				(type default)
			)
			(layer "B.SilkS")
		)
		(fp_poly
			(pts
				(xy 0.970026 0.4699) (xy -0.970026 0.4699) (xy -0.970026 -0.4699) (xy 0.970026 -0.4699)
			)
			(stroke
				(width 0)
				(type default)
			)
			(fill no)
			(layer "B.CrtYd")
		)
		(fp_line
			(start -0.508 -0.3048)
			(end -0.508 0.3048)
			(stroke
				(width 0.1)
				(type default)
			)
			(layer "B.Fab")
		)
		(fp_line
			(start -0.508 0.3048)
			(end 0.508 0.3048)
			(stroke
				(width 0.1)
				(type default)
			)
			(layer "B.Fab")
		)
		(fp_line
			(start 0.508 -0.3048)
			(end -0.508 -0.3048)
			(stroke
				(width 0.1)
				(type default)
			)
			(layer "B.Fab")
		)
		(fp_line
			(start 0.508 0.3048)
			(end 0.508 -0.3048)
			(stroke
				(width 0.1)
				(type default)
			)
			(layer "B.Fab")
		)
		(pad "1" smd circle
			(at 0.500126 0 180)
			(size 0.635 0.635)
			(layers "B.Cu" "B.Mask" "B.Paste")
			(net "XP1R0V_FPGA_VCCINT")
		)
		(pad "2" smd circle
			(at -0.500126 0 180)
			(size 0.635 0.635)
			(layers "B.Cu" "B.Mask" "B.Paste")
			(net "SG")
		)
	)
)
